# SCM (Grand Teton) — schematic netlist excerpt (pin names and nets, part order shuffled) for the footprints in the layout excerpt that follows; sources: Cadence DE-HDL packaged netlist, KiCad conversion of 12092022_DA0F0TMDCD0_F0T_Management_Board_D_brd_V3_OCP.brd

R96  Q_RES  33.2 1% CHIP  pkg 0402LF  page 13 : A = BMC_EMMC_RST_R_N ; B = BMC_EMMC_RST_N
R585  Q_RES  33.2 1% CHIP  pkg 0402LF  page 15 : A = BMC_RSTIND_N ; B = RST_SPI_FLASH_N

(kicad_pcb
	(version 20260206)
	(generator "pcbnew")
	(generator_version "10.0")
	(general
		(thickness 1.6)
		(legacy_teardrops no)
	)
	(paper "A4")
	(title_block
		(title "12092022_DA0F0TMDCD0_F0T_Management_Board_D_brd_V3_OCP.brd")
		(comment 1 "Grand Teton / footprints 171-172 of 1440")
	)
	(layers
		(0 "F.Cu" signal "TOP")
		(4 "In1.Cu" signal "GND")
		(6 "In2.Cu" signal "IN1")
		(8 "In3.Cu" signal "GND1")
		(10 "In4.Cu" signal "IN2")
		(12 "In5.Cu" signal "VCC")
		(14 "In6.Cu" signal "VCC1")
		(16 "In7.Cu" signal "IN3")
		(18 "In8.Cu" signal "GND2")
		(20 "In9.Cu" signal "IN4")
		(22 "In10.Cu" signal "GND3")
		(2 "B.Cu" signal "BOTTOM")
		(9 "F.Adhes" user "F.Adhesive")
		(11 "B.Adhes" user "B.Adhesive")
		(13 "F.Paste" user "Package Geometry/Pastemask Top")
		(15 "B.Paste" user "Package Geometry/Pastemask Bottom")
		(5 "F.SilkS" user "Ref Des/Silkscreen Top")
		(7 "B.SilkS" user "Ref Des/Silkscreen Bottom")
		(1 "F.Mask" user "Board Geometry/Soldermask Top")
		(3 "B.Mask" user "Board Geometry/Soldermask Bottom")
		(17 "Dwgs.User" user "User.Drawings")
		(19 "Cmts.User" user "User.Comments")
		(21 "Eco1.User" user "User.Eco1")
		(23 "Eco2.User" user "User.Eco2")
		(25 "Edge.Cuts" user "Board Geometry/Outline")
		(27 "Margin" user)
		(31 "F.CrtYd" user "Package Geometry/Place Bound Top")
		(29 "B.CrtYd" user "Package Geometry/Place Bound Bottom")
		(35 "F.Fab" user "Ref Des/Assembly Top")
		(33 "B.Fab" user "Ref Des/Assembly Bottom")
	)
	(footprint ""
		(layer "F.Cu")
		(at 64.1096 -70.84314 90)
		(property "Reference" "R96"
			(at 0 0 90)
			(layer "F.SilkS")
			(hide yes)
			(effects
				(font
					(size 1.27 1.27)
				)
			)
		)
		(property "Value" ""
			(at 0 0 90)
			(layer "F.Fab")
			(effects
				(font
					(size 1.27 1.27)
				)
			)
		)
		(duplicate_pad_numbers_are_jumpers no)
		(fp_line
			(start 0.7874 -0.4064)
			(end 0.7874 0.4064)
			(stroke
				(width 0.1524)
				(type default)
			)
			(layer "F.SilkS")
		)
		(fp_line
			(start -0.7874 -0.4064)
			(end 0.7874 -0.4064)
			(stroke
				(width 0.1524)
				(type default)
			)
			(layer "F.SilkS")
		)
		(fp_line
			(start 0.7874 0.4064)
			(end -0.7874 0.4064)
			(stroke
				(width 0.1524)
				(type default)
			)
			(layer "F.SilkS")
		)
		(fp_line
			(start -0.7874 0.4064)
			(end -0.7874 -0.4064)
			(stroke
				(width 0.1524)
				(type default)
			)
			(layer "F.SilkS")
		)
		(fp_line
			(start -0.12065 -0.305054)
			(end -0.12065 -0.2794)
			(stroke
				(width 0.1)
				(type default)
			)
			(layer "F.Fab")
		)
		(fp_line
			(start -0.67945 -0.305054)
			(end -0.12065 -0.305054)
			(stroke
				(width 0.1)
				(type default)
			)
			(layer "F.Fab")
		)
		(fp_line
			(start 0.67945 -0.3048)
			(end 0.67945 0.3048)
			(stroke
				(width 0.1)
				(type default)
			)
			(layer "F.Fab")
		)
		(fp_line
			(start 0.12065 -0.3048)
			(end 0.67945 -0.3048)
			(stroke
				(width 0.1)
				(type default)
			)
			(layer "F.Fab")
		)
		(fp_line
			(start 0.12065 -0.2794)
			(end 0.12065 -0.3048)
			(stroke
				(width 0.1)
				(type default)
			)
			(layer "F.Fab")
		)
		(fp_line
			(start -0.12065 -0.2794)
			(end 0.12065 -0.2794)
			(stroke
				(width 0.1)
				(type default)
			)
			(layer "F.Fab")
		)
		(fp_line
			(start 0.120396 0.2794)
			(end -0.12065 0.2794)
			(stroke
				(width 0.1)
				(type default)
			)
			(layer "F.Fab")
		)
		(fp_line
			(start -0.12065 0.2794)
			(end -0.12065 0.3048)
			(stroke
				(width 0.1)
				(type default)
			)
			(layer "F.Fab")
		)
		(fp_line
			(start 0.67945 0.3048)
			(end 0.120396 0.3048)
			(stroke
				(width 0.1)
				(type default)
			)
			(layer "F.Fab")
		)
		(fp_line
			(start 0.120396 0.3048)
			(end 0.120396 0.2794)
			(stroke
				(width 0.1)
				(type default)
			)
			(layer "F.Fab")
		)
		(fp_line
			(start -0.12065 0.3048)
			(end -0.67945 0.3048)
			(stroke
				(width 0.1)
				(type default)
			)
			(layer "F.Fab")
		)
		(fp_line
			(start -0.67945 0.3048)
			(end -0.67945 -0.305054)
			(stroke
				(width 0.1)
				(type default)
			)
			(layer "F.Fab")
		)
		(pad "1" smd circle
			(at -0.40005 0 90)
			(size 0 0)
			(layers "F.Cu" "F.Mask" "F.Paste")
			(net "BMC_EMMC_RST_R_N")
		)
		(pad "2" smd circle
			(at 0.40005 0 90)
			(size 0 0)
			(layers "F.Cu" "F.Mask" "F.Paste")
			(net "BMC_EMMC_RST_N")
		)
	)
	(footprint ""
		(layer "F.Cu")
		(at 71.80834 -23.68804 180)
		(property "Reference" "R585"
			(at 0 0 180)
			(layer "F.SilkS")
			(hide yes)
			(effects
				(font
					(size 1.27 1.27)
				)
			)
		)
		(property "Value" ""
			(at 0 0 180)
			(layer "F.Fab")
			(effects
				(font
					(size 1.27 1.27)
				)
			)
		)
		(duplicate_pad_numbers_are_jumpers no)
		(fp_line
			(start 0.7874 0.4064)
			(end -0.7874 0.4064)
			(stroke
				(width 0.1524)
				(type default)
			)
			(layer "F.SilkS")
		)
		(fp_line
			(start 0.7874 -0.4064)
			(end 0.7874 0.4064)
			(stroke
				(width 0.1524)
				(type default)
			)
			(layer "F.SilkS")
		)
		(fp_line
			(start -0.7874 0.4064)
			(end -0.7874 -0.4064)
			(stroke
				(width 0.1524)
				(type default)
			)
			(layer "F.SilkS")
		)
		(fp_line
			(start -0.7874 -0.4064)
			(end 0.7874 -0.4064)
			(stroke
				(width 0.1524)
				(type default)
			)
			(layer "F.SilkS")
		)
		(fp_line
			(start 0.67945 0.3048)
			(end 0.120396 0.3048)
			(stroke
				(width 0.1)
				(type default)
			)
			(layer "F.Fab")
		)
		(fp_line
			(start 0.67945 -0.3048)
			(end 0.67945 0.3048)
			(stroke
				(width 0.1)
				(type default)
			)
			(layer "F.Fab")
		)
		(fp_line
			(start 0.12065 -0.2794)
			(end 0.12065 -0.3048)
			(stroke
				(width 0.1)
				(type default)
			)
			(layer "F.Fab")
		)
		(fp_line
			(start 0.12065 -0.3048)
			(end 0.67945 -0.3048)
			(stroke
				(width 0.1)
				(type default)
			)
			(layer "F.Fab")
		)
		(fp_line
			(start 0.120396 0.3048)
			(end 0.120396 0.2794)
			(stroke
				(width 0.1)
				(type default)
			)
			(layer "F.Fab")
		)
		(fp_line
			(start 0.120396 0.2794)
			(end -0.12065 0.2794)
			(stroke
				(width 0.1)
				(type default)
			)
			(layer "F.Fab")
		)
		(fp_line
			(start -0.12065 0.3048)
			(end -0.67945 0.3048)
			(stroke
				(width 0.1)
				(type default)
			)
			(layer "F.Fab")
		)
		(fp_line
			(start -0.12065 0.2794)
			(end -0.12065 0.3048)
			(stroke
				(width 0.1)
				(type default)
			)
			(layer "F.Fab")
		)
		(fp_line
			(start -0.12065 -0.2794)
			(end 0.12065 -0.2794)
			(stroke
				(width 0.1)
				(type default)
			)
			(layer "F.Fab")
		)
		(fp_line
			(start -0.12065 -0.305054)
			(end -0.12065 -0.2794)
			(stroke
				(width 0.1)
				(type default)
			)
			(layer "F.Fab")
		)
		(fp_line
			(start -0.67945 0.3048)
			(end -0.67945 -0.305054)
			(stroke
				(width 0.1)
				(type default)
			)
			(layer "F.Fab")
		)
		(fp_line
			(start -0.67945 -0.305054)
			(end -0.12065 -0.305054)
			(stroke
				(width 0.1)
				(type default)
			)
			(layer "F.Fab")
		)
		(pad "1" smd circle
			(at -0.40005 0 180)
			(size 0 0)
			(layers "F.Cu" "F.Mask" "F.Paste")
			(net "BMC_RSTIND_N")
		)
		(pad "2" smd circle
			(at 0.40005 0 180)
			(size 0 0)
			(layers "F.Cu" "F.Mask" "F.Paste")
			(net "RST_SPI_FLASH_N")
		)
	)
)
